(kicad_pcb
	(version 20260206)
	(generator "pcbnew")
	(generator_version "10.0")
	(general
		(thickness 1.6)
		(legacy_teardrops no)
	)
	(paper "A4")
	(title_block
		(title "01162023_DA0F0TEBIF0_F0T_Expander_BD_F_brd_V02_OCP.brd")
		(comment 1 "Grand Teton / footprints 3022-3026 of 9728")
	)
	(layers
		(0 "F.Cu" signal "TOP")
		(4 "In1.Cu" signal "GND")
		(6 "In2.Cu" signal "VCC")
		(8 "In3.Cu" signal "VCC1")
		(10 "In4.Cu" signal "GND1")
		(12 "In5.Cu" signal "IN1")
		(14 "In6.Cu" signal "GND2")
		(16 "In7.Cu" signal "IN2")
		(18 "In8.Cu" signal "GND3")
		(20 "In9.Cu" signal "IN3")
		(22 "In10.Cu" signal "GND4")
		(24 "In11.Cu" signal "IN4")
		(26 "In12.Cu" signal "GND5")
		(28 "In13.Cu" signal "IN5")
		(30 "In14.Cu" signal "GND6")
		(32 "In15.Cu" signal "IN6")
		(34 "In16.Cu" signal "GND7")
		(2 "B.Cu" signal "BOTTOM")
		(9 "F.Adhes" user "F.Adhesive")
		(11 "B.Adhes" user "B.Adhesive")
		(13 "F.Paste" user "Package Geometry/Pastemask Top")
		(15 "B.Paste" user "Package Geometry/Pastemask Bottom")
		(5 "F.SilkS" user "Ref Des/Silkscreen Top")
		(7 "B.SilkS" user "Ref Des/Silkscreen Bottom")
		(1 "F.Mask" user "Board Geometry/Soldermask Top")
		(3 "B.Mask" user "Board Geometry/Soldermask Bottom")
		(17 "Dwgs.User" user "User.Drawings")
		(19 "Cmts.User" user "User.Comments")
		(21 "Eco1.User" user "User.Eco1")
		(23 "Eco2.User" user "User.Eco2")
		(25 "Edge.Cuts" user "Board Geometry/Outline")
		(27 "Margin" user)
		(31 "F.CrtYd" user "Package Geometry/Place Bound Top")
		(29 "B.CrtYd" user "Package Geometry/Place Bound Bottom")
		(35 "F.Fab" user "Ref Des/Assembly Top")
		(33 "B.Fab" user "Ref Des/Assembly Bottom")
	)
	(footprint ""
		(layer "F.Cu")
		(at 122.991118 -55.663846 90)
		(property "Reference" "PU55"
			(at -1.267206 2.608834 90)
			(unlocked yes)
			(layer "F.SilkS")
			(effects
				(font
					(size 0.7874 0.5842)
					(thickness 0.1524)
				)
				(justify left)
			)
		)
		(property "Value" ""
			(at 0 0 90)
			(layer "F.Fab")
			(effects
				(font
					(size 1.27 1.27)
				)
			)
		)
		(duplicate_pad_numbers_are_jumpers no)
		(fp_line
			(start 1.943608 -1.549908)
			(end 1.943608 1.549908)
			(stroke
				(width 0.1524)
				(type default)
			)
			(layer "F.SilkS")
		)
		(fp_line
			(start -1.943608 -1.549908)
			(end 1.943608 -1.549908)
			(stroke
				(width 0.1524)
				(type default)
			)
			(layer "F.SilkS")
		)
		(fp_line
			(start 1.943608 1.549908)
			(end -1.943608 1.549908)
			(stroke
				(width 0.1524)
				(type default)
			)
			(layer "F.SilkS")
		)
		(fp_line
			(start -1.943608 1.549908)
			(end -1.943608 -1.549908)
			(stroke
				(width 0.1524)
				(type default)
			)
			(layer "F.SilkS")
		)
		(fp_poly
			(pts
				(xy -2.019808 -1.549908) (xy -1.257808 -1.549908) (xy -1.257808 -1.880108) (xy -2.019808 -1.880108)
			)
			(stroke
				(width 0)
				(type default)
			)
			(fill yes)
			(layer "F.SilkS")
		)
		(fp_line
			(start 1.549908 -1.549908)
			(end 1.549908 1.549908)
			(stroke
				(width 0.1)
				(type default)
			)
			(layer "F.Fab")
		)
		(fp_line
			(start -1.549908 -1.549908)
			(end 1.549908 -1.549908)
			(stroke
				(width 0.1)
				(type default)
			)
			(layer "F.Fab")
		)
		(fp_line
			(start 1.549908 1.549908)
			(end -1.549908 1.549908)
			(stroke
				(width 0.1)
				(type default)
			)
			(layer "F.Fab")
		)
		(fp_line
			(start -1.549908 1.549908)
			(end -1.549908 -1.549908)
			(stroke
				(width 0.1)
				(type default)
			)
			(layer "F.Fab")
		)
		(fp_poly
			(pts
				(xy -2.019808 -1.549908) (xy -1.257808 -1.549908) (xy -1.257808 -1.880108) (xy -2.019808 -1.880108)
			)
			(stroke
				(width 0)
				(type default)
			)
			(fill yes)
			(layer "F.Fab")
		)
		(pad "1" smd rect
			(at -1.500124 -1.249934)
			(size 0.2794 0.6096)
			(layers "F.Cu" "F.Mask" "F.Paste")
			(net "P3V3_SSD4")
		)
		(pad "2" smd rect
			(at -1.500124 -0.750062)
			(size 0.2794 0.6096)
			(layers "F.Cu" "F.Mask" "F.Paste")
			(net "P3V3_SSD4")
		)
		(pad "3" smd rect
			(at -1.500124 -0.249936)
			(size 0.2794 0.6096)
			(layers "F.Cu" "F.Mask" "F.Paste")
			(net "P3V3_SSD4")
		)
		(pad "4" smd rect
			(at -1.500124 0.249936)
			(size 0.2794 0.6096)
			(layers "F.Cu" "F.Mask" "F.Paste")
			(net "P3V3_SSD4")
		)
		(pad "5" smd rect
			(at -1.500124 0.750062)
			(size 0.2794 0.6096)
			(layers "F.Cu" "F.Mask" "F.Paste")
			(net "P3V3_SSD4")
		)
		(pad "6" smd rect
			(at -1.500124 1.249934)
			(size 0.2794 0.6096)
			(layers "F.Cu" "F.Mask" "F.Paste")
			(net "GND")
		)
		(pad "7" smd rect
			(at 1.500124 1.249934)
			(size 0.2794 0.6096)
			(layers "F.Cu" "F.Mask" "F.Paste")
			(net "P3V3_SSD4_SS")
		)
		(pad "8" smd rect
			(at 1.500124 0.750062)
			(size 0.2794 0.6096)
			(layers "F.Cu" "F.Mask" "F.Paste")
			(net "PWRGD_P3V3_SSD4")
		)
		(pad "9" smd rect
			(at 1.500124 0.249936)
			(size 0.2794 0.6096)
			(layers "F.Cu" "F.Mask" "F.Paste")
			(net "P3V3_SSD4_OCP")
		)
		(pad "10" smd rect
			(at 1.500124 -0.249936)
			(size 0.2794 0.6096)
			(layers "F.Cu" "F.Mask" "F.Paste")
			(net "P5V_AUX")
		)
		(pad "11" smd rect
			(at 1.500124 -0.750062)
			(size 0.2794 0.6096)
			(layers "F.Cu" "F.Mask" "F.Paste")
			(net "SSD4_AUX_P3V3_EN_R")
		)
		(pad "12" smd rect
			(at 1.500124 -1.249934)
			(size 0.2794 0.6096)
			(layers "F.Cu" "F.Mask" "F.Paste")
			(net "P3V3_AUX")
		)
		(pad "13" smd rect
			(at 0 0 90)
			(size 1.9812 2.7178)
			(layers "F.Cu" "F.Mask" "F.Paste")
			(net "P3V3_AUX")
		)
		(zone
			(layer "F.Cu")
			(hatch none 0.5)
			(connect_pads
				(clearance 0)
			)
			(min_thickness 0.25)
			(keepout
				(tracks not_allowed)
				(vias allowed)
				(pads allowed)
				(copperpour not_allowed)
				(footprints allowed)
			)
			(placement
				(enabled no)
				(sheetname "")
			)
			(fill
				(thermal_gap 0.5)
				(thermal_bridge_width 0.5)
				(island_removal_mode 0)
			)
			(polygon
				(pts
					(xy 121.441718 -56.806846) (xy 121.568718 -56.806846) (xy 124.540518 -56.806846) (xy 124.541026 -56.806846)
					(xy 124.541026 -54.520846) (xy 124.540518 -54.520846) (xy 124.413518 -54.520846) (xy 122.991118 -54.520846)
					(xy 122.991118 -54.622446) (xy 124.413518 -54.622446) (xy 124.413518 -56.705246) (xy 121.568718 -56.705246)
					(xy 121.568718 -54.622446) (xy 122.965718 -54.622446) (xy 122.965718 -54.520846) (xy 121.568718 -54.520846)
					(xy 121.441718 -54.520846) (xy 121.44121 -54.520846) (xy 121.44121 -56.806846)
				)
			)
		)
	)
	(footprint ""
		(layer "F.Cu")
		(at 234.355894 -183.02478 180)
		(property "Reference" "D12"
			(at 1.326388 1.601724 0)
			(unlocked yes)
			(layer "F.SilkS")
			(effects
				(font
					(size 0.7874 0.5842)
					(thickness 0.1524)
				)
				(justify left)
			)
		)
		(property "Value" ""
			(at 0 0 180)
			(layer "F.Fab")
			(effects
				(font
					(size 1.27 1.27)
				)
			)
		)
		(duplicate_pad_numbers_are_jumpers no)
		(fp_line
			(start 2.032 0.7112)
			(end -1.651 0.7112)
			(stroke
				(width 0.1524)
				(type default)
			)
			(layer "F.SilkS")
		)
		(fp_line
			(start 2.032 -0.7112)
			(end 2.032 0.7112)
			(stroke
				(width 0.1524)
				(type default)
			)
			(layer "F.SilkS")
		)
		(fp_line
			(start 1.905 -0.6858)
			(end 1.905 0.6858)
			(stroke
				(width 0.1524)
				(type default)
			)
			(layer "F.SilkS")
		)
		(fp_line
			(start 1.778 0.6858)
			(end 1.778 -0.6858)
			(stroke
				(width 0.1524)
				(type default)
			)
			(layer "F.SilkS")
		)
		(fp_line
			(start 1.651 -0.6858)
			(end 1.651 0.6858)
			(stroke
				(width 0.1524)
				(type default)
			)
			(layer "F.SilkS")
		)
		(fp_line
			(start 0.299974 -0.500126)
			(end 0.299974 0.500126)
			(stroke
				(width 0.1524)
				(type default)
			)
			(layer "F.SilkS")
		)
		(fp_line
			(start 0.199898 0)
			(end -0.299974 -0.500126)
			(stroke
				(width 0.1524)
				(type default)
			)
			(layer "F.SilkS")
		)
		(fp_line
			(start -0.299974 0.500126)
			(end 0.199898 0)
			(stroke
				(width 0.1524)
				(type default)
			)
			(layer "F.SilkS")
		)
		(fp_line
			(start -0.299974 -0.500126)
			(end -0.299974 0.500126)
			(stroke
				(width 0.1524)
				(type default)
			)
			(layer "F.SilkS")
		)
		(fp_line
			(start -1.651 0.7112)
			(end -1.651 -0.7112)
			(stroke
				(width 0.1524)
				(type default)
			)
			(layer "F.SilkS")
		)
		(fp_line
			(start -1.651 -0.7112)
			(end 2.032 -0.7112)
			(stroke
				(width 0.1524)
				(type default)
			)
			(layer "F.SilkS")
		)
		(fp_line
			(start 1.35001 0.175006)
			(end 0.899922 0.175006)
			(stroke
				(width 0.1)
				(type default)
			)
			(layer "F.Fab")
		)
		(fp_line
			(start 1.35001 -0.225044)
			(end 1.35001 0.175006)
			(stroke
				(width 0.1)
				(type default)
			)
			(layer "F.Fab")
		)
		(fp_line
			(start 0.899922 0.700024)
			(end -0.899922 0.700024)
			(stroke
				(width 0.1)
				(type default)
			)
			(layer "F.Fab")
		)
		(fp_line
			(start 0.899922 0.175006)
			(end 0.899922 0.700024)
			(stroke
				(width 0.1)
				(type default)
			)
			(layer "F.Fab")
		)
		(fp_line
			(start 0.899922 -0.225044)
			(end 1.35001 -0.225044)
			(stroke
				(width 0.1)
				(type default)
			)
			(layer "F.Fab")
		)
		(fp_line
			(start 0.899922 -0.700024)
			(end 0.899922 -0.225044)
			(stroke
				(width 0.1)
				(type default)
			)
			(layer "F.Fab")
		)
		(fp_line
			(start 0.299974 -0.500126)
			(end 0.299974 0.500126)
			(stroke
				(width 0.1)
				(type default)
			)
			(layer "F.Fab")
		)
		(fp_line
			(start 0.199898 0)
			(end -0.299974 -0.500126)
			(stroke
				(width 0.1)
				(type default)
			)
			(layer "F.Fab")
		)
		(fp_line
			(start -0.299974 0.500126)
			(end 0.199898 0)
			(stroke
				(width 0.1)
				(type default)
			)
			(layer "F.Fab")
		)
		(fp_line
			(start -0.299974 -0.500126)
			(end -0.299974 0.500126)
			(stroke
				(width 0.1)
				(type default)
			)
			(layer "F.Fab")
		)
		(fp_line
			(start -0.899922 0.700024)
			(end -0.899922 0.175006)
			(stroke
				(width 0.1)
				(type default)
			)
			(layer "F.Fab")
		)
		(fp_line
			(start -0.899922 0.175006)
			(end -1.35001 0.175006)
			(stroke
				(width 0.1)
				(type default)
			)
			(layer "F.Fab")
		)
		(fp_line
			(start -0.899922 -0.225044)
			(end -0.899922 -0.700024)
			(stroke
				(width 0.1)
				(type default)
			)
			(layer "F.Fab")
		)
		(fp_line
			(start -0.899922 -0.700024)
			(end 0.899922 -0.700024)
			(stroke
				(width 0.1)
				(type default)
			)
			(layer "F.Fab")
		)
		(fp_line
			(start -1.35001 0.175006)
			(end -1.35001 -0.225044)
			(stroke
				(width 0.1)
				(type default)
			)
			(layer "F.Fab")
		)
		(fp_line
			(start -1.35001 -0.225044)
			(end -0.899922 -0.225044)
			(stroke
				(width 0.1)
				(type default)
			)
			(layer "F.Fab")
		)
		(fp_text user "-"
			(at 1.820418 0.676148 180)
			(unlocked yes)
			(layer "F.SilkS")
			(effects
				(font
					(size 1.905 1.4224)
					(thickness 0.1524)
				)
				(justify left)
			)
		)
		(fp_text user "+"
			(at -2.860294 -1.041908 180)
			(unlocked yes)
			(layer "F.SilkS")
			(effects
				(font
					(size 1.905 1.4224)
					(thickness 0.1524)
				)
				(justify left)
			)
		)
		(fp_text user "-"
			(at 1.8288 -0.24765 180)
			(unlocked yes)
			(layer "F.Fab")
			(effects
				(font
					(size 1.905 1.4224)
					(thickness 0.1524)
				)
				(justify left)
			)
		)
		(fp_text user "+"
			(at -2.794 -0.19685 180)
			(unlocked yes)
			(layer "F.Fab")
			(effects
				(font
					(size 1.905 1.4224)
					(thickness 0.1524)
				)
				(justify left)
			)
		)
		(pad "1" smd rect
			(at -1.0922 0)
			(size 0.8128 0.8636)
			(layers "F.Cu" "F.Mask" "F.Paste")
			(net "RST_BIC_EXTRST_N")
		)
		(pad "2" smd rect
			(at 1.0922 0 180)
			(size 0.8128 0.8636)
			(layers "F.Cu" "F.Mask" "F.Paste")
			(net "RST_FPGA_BIC_R_N")
		)
	)
	(footprint ""
		(layer "F.Cu")
		(at 284.264354 -166.302944 90)
		(property "Reference" "R250"
			(at 0 0 90)
			(layer "F.SilkS")
			(hide yes)
			(effects
				(font
					(size 1.27 1.27)
				)
			)
		)
		(property "Value" ""
			(at 0 0 90)
			(layer "F.Fab")
			(effects
				(font
					(size 1.27 1.27)
				)
			)
		)
		(duplicate_pad_numbers_are_jumpers no)
		(fp_line
			(start 0.7874 -0.4064)
			(end 0.7874 0.4064)
			(stroke
				(width 0.1524)
				(type default)
			)
			(layer "F.SilkS")
		)
		(fp_line
			(start -0.7874 -0.4064)
			(end 0.7874 -0.4064)
			(stroke
				(width 0.1524)
				(type default)
			)
			(layer "F.SilkS")
		)
		(fp_line
			(start 0.7874 0.4064)
			(end -0.7874 0.4064)
			(stroke
				(width 0.1524)
				(type default)
			)
			(layer "F.SilkS")
		)
		(fp_line
			(start -0.7874 0.4064)
			(end -0.7874 -0.4064)
			(stroke
				(width 0.1524)
				(type default)
			)
			(layer "F.SilkS")
		)
		(fp_line
			(start -0.12065 -0.305054)
			(end -0.12065 -0.2794)
			(stroke
				(width 0.1)
				(type default)
			)
			(layer "F.Fab")
		)
		(fp_line
			(start -0.67945 -0.305054)
			(end -0.12065 -0.305054)
			(stroke
				(width 0.1)
				(type default)
			)
			(layer "F.Fab")
		)
		(fp_line
			(start 0.67945 -0.3048)
			(end 0.67945 0.3048)
			(stroke
				(width 0.1)
				(type default)
			)
			(layer "F.Fab")
		)
		(fp_line
			(start 0.12065 -0.3048)
			(end 0.67945 -0.3048)
			(stroke
				(width 0.1)
				(type default)
			)
			(layer "F.Fab")
		)
		(fp_line
			(start 0.12065 -0.2794)
			(end 0.12065 -0.3048)
			(stroke
				(width 0.1)
				(type default)
			)
			(layer "F.Fab")
		)
		(fp_line
			(start -0.12065 -0.2794)
			(end 0.12065 -0.2794)
			(stroke
				(width 0.1)
				(type default)
			)
			(layer "F.Fab")
		)
		(fp_line
			(start 0.120396 0.2794)
			(end -0.12065 0.2794)
			(stroke
				(width 0.1)
				(type default)
			)
			(layer "F.Fab")
		)
		(fp_line
			(start -0.12065 0.2794)
			(end -0.12065 0.3048)
			(stroke
				(width 0.1)
				(type default)
			)
			(layer "F.Fab")
		)
		(fp_line
			(start 0.67945 0.3048)
			(end 0.120396 0.3048)
			(stroke
				(width 0.1)
				(type default)
			)
			(layer "F.Fab")
		)
		(fp_line
			(start 0.120396 0.3048)
			(end 0.120396 0.2794)
			(stroke
				(width 0.1)
				(type default)
			)
			(layer "F.Fab")
		)
		(fp_line
			(start -0.12065 0.3048)
			(end -0.67945 0.3048)
			(stroke
				(width 0.1)
				(type default)
			)
			(layer "F.Fab")
		)
		(fp_line
			(start -0.67945 0.3048)
			(end -0.67945 -0.305054)
			(stroke
				(width 0.1)
				(type default)
			)
			(layer "F.Fab")
		)
		(pad "1" smd circle
			(at -0.40005 0 90)
			(size 0 0)
			(layers "F.Cu" "F.Mask" "F.Paste")
			(net "RST_NIC4_PERST1_R_N")
		)
		(pad "2" smd circle
			(at 0.40005 0 90)
			(size 0 0)
			(layers "F.Cu" "F.Mask" "F.Paste")
			(net "RST_HP_NIC4_BUF_N")
		)
	)
	(footprint ""
		(layer "F.Cu")
		(at 310.443626 -42.84091)
		(property "Reference" "R616"
			(at 0 0 0)
			(layer "F.SilkS")
			(hide yes)
			(effects
				(font
					(size 1.27 1.27)
				)
			)
		)
		(property "Value" ""
			(at 0 0 0)
			(layer "F.Fab")
			(effects
				(font
					(size 1.27 1.27)
				)
			)
		)
		(duplicate_pad_numbers_are_jumpers no)
		(fp_line
			(start -0.7874 -0.4064)
			(end 0.7874 -0.4064)
			(stroke
				(width 0.1524)
				(type default)
			)
			(layer "F.SilkS")
		)
		(fp_line
			(start -0.7874 0.4064)
			(end -0.7874 -0.4064)
			(stroke
				(width 0.1524)
				(type default)
			)
			(layer "F.SilkS")
		)
		(fp_line
			(start 0.7874 -0.4064)
			(end 0.7874 0.4064)
			(stroke
				(width 0.1524)
				(type default)
			)
			(layer "F.SilkS")
		)
		(fp_line
			(start 0.7874 0.4064)
			(end -0.7874 0.4064)
			(stroke
				(width 0.1524)
				(type default)
			)
			(layer "F.SilkS")
		)
		(fp_line
			(start -0.67945 -0.305054)
			(end -0.12065 -0.305054)
			(stroke
				(width 0.1)
				(type default)
			)
			(layer "F.Fab")
		)
		(fp_line
			(start -0.67945 0.3048)
			(end -0.67945 -0.305054)
			(stroke
				(width 0.1)
				(type default)
			)
			(layer "F.Fab")
		)
		(fp_line
			(start -0.12065 -0.305054)
			(end -0.12065 -0.2794)
			(stroke
				(width 0.1)
				(type default)
			)
			(layer "F.Fab")
		)
		(fp_line
			(start -0.12065 -0.2794)
			(end 0.12065 -0.2794)
			(stroke
				(width 0.1)
				(type default)
			)
			(layer "F.Fab")
		)
		(fp_line
			(start -0.12065 0.2794)
			(end -0.12065 0.3048)
			(stroke
				(width 0.1)
				(type default)
			)
			(layer "F.Fab")
		)
		(fp_line
			(start -0.12065 0.3048)
			(end -0.67945 0.3048)
			(stroke
				(width 0.1)
				(type default)
			)
			(layer "F.Fab")
		)
		(fp_line
			(start 0.120396 0.2794)
			(end -0.12065 0.2794)
			(stroke
				(width 0.1)
				(type default)
			)
			(layer "F.Fab")
		)
		(fp_line
			(start 0.120396 0.3048)
			(end 0.120396 0.2794)
			(stroke
				(width 0.1)
				(type default)
			)
			(layer "F.Fab")
		)
		(fp_line
			(start 0.12065 -0.3048)
			(end 0.67945 -0.3048)
			(stroke
				(width 0.1)
				(type default)
			)
			(layer "F.Fab")
		)
		(fp_line
			(start 0.12065 -0.2794)
			(end 0.12065 -0.3048)
			(stroke
				(width 0.1)
				(type default)
			)
			(layer "F.Fab")
		)
		(fp_line
			(start 0.67945 -0.3048)
			(end 0.67945 0.3048)
			(stroke
				(width 0.1)
				(type default)
			)
			(layer "F.Fab")
		)
		(fp_line
			(start 0.67945 0.3048)
			(end 0.120396 0.3048)
			(stroke
				(width 0.1)
				(type default)
			)
			(layer "F.Fab")
		)
		(pad "1" smd circle
			(at -0.40005 0)
			(size 0 0)
			(layers "F.Cu" "F.Mask" "F.Paste")
			(net "SSD10_ADC_A1")
		)
		(pad "2" smd circle
			(at 0.40005 0)
			(size 0 0)
			(layers "F.Cu" "F.Mask" "F.Paste")
			(net "P3V3_AUX")
		)
	)
	(footprint ""
		(layer "F.Cu")
		(at 344.678 -205.232 90)
		(property "Reference" "R4145"
			(at 0 0 90)
			(layer "F.SilkS")
			(hide yes)
			(effects
				(font
					(size 1.27 1.27)
				)
			)
		)
		(property "Value" ""
			(at 0 0 90)
			(layer "F.Fab")
			(effects
				(font
					(size 1.27 1.27)
				)
			)
		)
		(duplicate_pad_numbers_are_jumpers no)
		(fp_line
			(start 0.7874 -0.4064)
			(end 0.7874 0.4064)
			(stroke
				(width 0.1524)
				(type default)
			)
			(layer "F.SilkS")
		)
		(fp_line
			(start -0.7874 -0.4064)
			(end 0.7874 -0.4064)
			(stroke
				(width 0.1524)
				(type default)
			)
			(layer "F.SilkS")
		)
		(fp_line
			(start 0.7874 0.4064)
			(end -0.7874 0.4064)
			(stroke
				(width 0.1524)
				(type default)
			)
			(layer "F.SilkS")
		)
		(fp_line
			(start -0.7874 0.4064)
			(end -0.7874 -0.4064)
			(stroke
				(width 0.1524)
				(type default)
			)
			(layer "F.SilkS")
		)
		(fp_line
			(start -0.12065 -0.305054)
			(end -0.12065 -0.2794)
			(stroke
				(width 0.1)
				(type default)
			)
			(layer "F.Fab")
		)
		(fp_line
			(start -0.67945 -0.305054)
			(end -0.12065 -0.305054)
			(stroke
				(width 0.1)
				(type default)
			)
			(layer "F.Fab")
		)
		(fp_line
			(start 0.67945 -0.3048)
			(end 0.67945 0.3048)
			(stroke
				(width 0.1)
				(type default)
			)
			(layer "F.Fab")
		)
		(fp_line
			(start 0.12065 -0.3048)
			(end 0.67945 -0.3048)
			(stroke
				(width 0.1)
				(type default)
			)
			(layer "F.Fab")
		)
		(fp_line
			(start 0.12065 -0.2794)
			(end 0.12065 -0.3048)
			(stroke
				(width 0.1)
				(type default)
			)
			(layer "F.Fab")
		)
		(fp_line
			(start -0.12065 -0.2794)
			(end 0.12065 -0.2794)
			(stroke
				(width 0.1)
				(type default)
			)
			(layer "F.Fab")
		)
		(fp_line
			(start 0.120396 0.2794)
			(end -0.12065 0.2794)
			(stroke
				(width 0.1)
				(type default)
			)
			(layer "F.Fab")
		)
		(fp_line
			(start -0.12065 0.2794)
			(end -0.12065 0.3048)
			(stroke
				(width 0.1)
				(type default)
			)
			(layer "F.Fab")
		)
		(fp_line
			(start 0.67945 0.3048)
			(end 0.120396 0.3048)
			(stroke
				(width 0.1)
				(type default)
			)
			(layer "F.Fab")
		)
		(fp_line
			(start 0.120396 0.3048)
			(end 0.120396 0.2794)
			(stroke
				(width 0.1)
				(type default)
			)
			(layer "F.Fab")
		)
		(fp_line
			(start -0.12065 0.3048)
			(end -0.67945 0.3048)
			(stroke
				(width 0.1)
				(type default)
			)
			(layer "F.Fab")
		)
		(fp_line
			(start -0.67945 0.3048)
			(end -0.67945 -0.305054)
			(stroke
				(width 0.1)
				(type default)
			)
			(layer "F.Fab")
		)
		(pad "1" smd circle
			(at -0.40005 0 90)
			(size 0 0)
			(layers "F.Cu" "F.Mask" "F.Paste")
			(net "RST_SSD15_PERST_R_N")
		)
		(pad "2" smd circle
			(at 0.40005 0 90)
			(size 0 0)
			(layers "F.Cu" "F.Mask" "F.Paste")
			(net "RST_SSD15_PERST_N")
		)
	)
)
